FILE_TYPE = CONNECTIVITY;
{Allegro Design Entry HDL 17.2-2016 S081 (4005846) 1/11/2022}
"PAGE_NUMBER" = 234;
0"NC";
1"P12V_AUX\g";
2"P12V_AUX\g";
3"GND\g";
4"GND\g";
5"FM_P12V_HSC_EN_R";
6"MB0_P12V_STBY_PWRGD";
7"FM_P12V_HSC_EN_N";
8"P12V_AUX_BLEEDING";
9"FM_P12V_HSC_EN_R_N";
%"Q_RES"
"2","(14600,4050)","0","pure_quanta","I10";
;
PART_NUMBER"CS24702JB10"
VALUE"4.7K"
TOLERANCE"5%"
PACK_TYPE"0402LF"
MATERIAL"CHIP"
WATTAGE"1/16W"
$LOCATION"R2530"
CDS_LIB"pure_quanta"
CDS_LOCATION"R2530"
$SEC"1"
CDS_SEC"1";
"A"
$PN"1"2;
"B"
$PN"2"8;
%"UNIVERSAL_POWER"
"1","(14600,4300)","0","logical_power","I11";
;
HDL_POWER"P12V_AUX"
CDS_LIB"logical_power";
"A"2;
%"MOSFET_NCH_GDS_ESD_PROTECTED"
"1","(14000,3450)","0","pure_quanta","I14";
;
PART_NUMBER"BAM70020002"
PART_TYPE"SMLF"
VALUE"2N7002K"
MATERIAL"IC"
LOCATION"Q54"
NEEDS_NO_SIZE"TRUE"
CDS_LMAN_SYM_OUTLINE"-125,150,125,-150"
CDS_LIB"pure_quanta"
$SEC"1"
CDS_SEC"1";
"S"
$PN"S"4;
"G"
$PN"G"9;
"D"
$PN"D"8;
%"UNIVERSAL_GND"
"1","(14025,3050)","0","logical_power","I15";
;
HDL_POWER"GND"
CDS_LIB"logical_power";
"A"4;
%"Q_RES"
"1","(10325,3125)","0","pure_quanta","I3";
;
PART_NUMBER"CS00002JB13"
VALUE"0"
PACK_TYPE"0402LF"
WATTAGE"1/16W"
MATERIAL"CHIP"
TOLERANCE"5%"
$LOCATION"R2531"
CDS_LIB"pure_quanta"
CDS_LOCATION"R2531"
$SEC"1"
CDS_SEC"1";
"B"
$PN"2"5;
"A"
$PN"1"6;
%"UNIVERSAL_GND"
"1","(11650,2775)","0","logical_power","I5";
;
CDS_LIB"logical_power"
HDL_POWER"GND";
"A"3;
%"MOSFET_NCH_GDS_ESD_PROTECTED"
"1","(11625,3125)","0","pure_quanta","I6";
;
PART_NUMBER"BAM70020002"
MATERIAL"IC"
VALUE"2N7002K"
PART_TYPE"SMLF"
$LOCATION"U158"
NEEDS_NO_SIZE"TRUE"
CDS_LMAN_SYM_OUTLINE"-125,150,125,-150"
CDS_LIB"pure_quanta"
CDS_LOCATION"U158"
$SEC"1"
CDS_SEC"1";
"S"
$PN"S"3;
"G"
$PN"G"5;
"D"
$PN"D"7;
%"Q_RES"
"1","(12575,3450)","0","pure_quanta","I7";
;
PART_NUMBER"CS00002JB13"
MATERIAL"CHIP"
PACK_TYPE"0402LF"
WATTAGE"1/16W"
VALUE"0"
TOLERANCE"5%"
$LOCATION"R2529"
CDS_LIB"pure_quanta"
CDS_LOCATION"R2529"
$SEC"1"
CDS_SEC"1";
"B"
$PN"2"9;
"A"
$PN"1"7;
%"Q_RES"
"2","(11650,3850)","0","pure_quanta","I8";
;
PART_NUMBER"CS41002FB09"
WATTAGE"1/16W"
MATERIAL"CHIP"
TOLERANCE"1%"
VALUE"100K"
PACK_TYPE"0402LF"
$LOCATION"R2528"
CDS_LIB"pure_quanta"
CDS_LOCATION"R2528"
$SEC"1"
CDS_SEC"1";
"A"
$PN"1"1;
"B"
$PN"2"7;
%"UNIVERSAL_POWER"
"1","(11650,4100)","0","logical_power","I9";
;
HDL_POWER"P12V_AUX"
CDS_LIB"logical_power";
"A"1;
END.
